# T6G (Grand Teton) — schematic netlist excerpt (pin names and nets, part order shuffled) for the footprints in the layout excerpt that follows; sources: Cadence DE-HDL packaged netlist, KiCad conversion of 04192023_DAF0TMB3IC0_F0TG_MB_C_brd_V02_OCP.brd

PR3968  Q_RES  9.31K 1% CHIP  pkg 0402LF  page 146 : A = P12V_E1S_CB_0 ; B = GND

Q126  MOSFET_NCH_DUAL  PJT138K IC  pkg SOT363XD  page 146
  S1  = GND
  G1  = P3V3_E1S_EN_0_R
  D2  = P3V3_E1S_UV_0_R
  S2  = GND
  G2  = P3V3_E1S_0_EN_G
  D1  = P3V3_E1S_0_EN_G

(kicad_pcb
	(version 20260206)
	(generator "pcbnew")
	(generator_version "10.0")
	(general
		(thickness 1.6)
		(legacy_teardrops no)
	)
	(paper "A4")
	(title_block
		(title "04192023_DAF0TMB3IC0_F0TG_MB_C_brd_V02_OCP.brd")
		(comment 1 "Grand Teton / footprints 1005-1006 of 8354")
	)
	(layers
		(0 "F.Cu" signal "TOP")
		(4 "In1.Cu" signal "GND")
		(6 "In2.Cu" signal "IN1")
		(8 "In3.Cu" signal "GND1")
		(10 "In4.Cu" signal "IN2")
		(12 "In5.Cu" signal "GND2")
		(14 "In6.Cu" signal "IN3")
		(16 "In7.Cu" signal "GND3")
		(18 "In8.Cu" signal "VCC")
		(20 "In9.Cu" signal "VCC1")
		(22 "In10.Cu" signal "GND4")
		(24 "In11.Cu" signal "IN4")
		(26 "In12.Cu" signal "GND5")
		(28 "In13.Cu" signal "IN5")
		(30 "In14.Cu" signal "GND6")
		(32 "In15.Cu" signal "IN6")
		(34 "In16.Cu" signal "GND7")
		(2 "B.Cu" signal "BOTTOM")
		(9 "F.Adhes" user "F.Adhesive")
		(11 "B.Adhes" user "B.Adhesive")
		(13 "F.Paste" user "Package Geometry/Pastemask Top")
		(15 "B.Paste" user "Package Geometry/Pastemask Bottom")
		(5 "F.SilkS" user "Ref Des/Silkscreen Top")
		(7 "B.SilkS" user "Ref Des/Silkscreen Bottom")
		(1 "F.Mask" user "Board Geometry/Soldermask Top")
		(3 "B.Mask" user "Board Geometry/Soldermask Bottom")
		(17 "Dwgs.User" user "User.Drawings")
		(19 "Cmts.User" user "User.Comments")
		(21 "Eco1.User" user "User.Eco1")
		(23 "Eco2.User" user "User.Eco2")
		(25 "Edge.Cuts" user "Board Geometry/Outline")
		(27 "Margin" user)
		(31 "F.CrtYd" user "Package Geometry/Place Bound Top")
		(29 "B.CrtYd" user "Package Geometry/Place Bound Bottom")
		(35 "F.Fab" user "Ref Des/Assembly Top")
		(33 "B.Fab" user "Ref Des/Assembly Bottom")
	)
	(footprint ""
		(layer "F.Cu")
		(at 254.362966 -68.946522)
		(property "Reference" "Q126"
			(at -1.4224 -1.768348 0)
			(unlocked yes)
			(layer "F.SilkS")
			(effects
				(font
					(size 0.7874 0.5842)
					(thickness 0.1524)
				)
				(justify left)
			)
		)
		(property "Value" ""
			(at 0 0 0)
			(layer "F.Fab")
			(effects
				(font
					(size 1.27 1.27)
				)
			)
		)
		(duplicate_pad_numbers_are_jumpers no)
		(fp_line
			(start -1.332738 -1.100074)
			(end -0.4826 -1.100074)
			(stroke
				(width 0.1524)
				(type default)
			)
			(layer "F.SilkS")
		)
		(fp_line
			(start -1.332738 1.100074)
			(end -1.332738 -1.100074)
			(stroke
				(width 0.1524)
				(type default)
			)
			(layer "F.SilkS")
		)
		(fp_line
			(start -0.4826 -1.100074)
			(end 0 -0.541274)
			(stroke
				(width 0.1524)
				(type default)
			)
			(layer "F.SilkS")
		)
		(fp_line
			(start 0 -0.541274)
			(end 0.4826 -1.100074)
			(stroke
				(width 0.1524)
				(type default)
			)
			(layer "F.SilkS")
		)
		(fp_line
			(start 0.4826 -1.100074)
			(end 1.332738 -1.100074)
			(stroke
				(width 0.1524)
				(type default)
			)
			(layer "F.SilkS")
		)
		(fp_line
			(start 1.332738 -1.100074)
			(end 1.332738 1.100074)
			(stroke
				(width 0.1524)
				(type default)
			)
			(layer "F.SilkS")
		)
		(fp_line
			(start 1.332738 1.100074)
			(end -1.332738 1.100074)
			(stroke
				(width 0.1524)
				(type default)
			)
			(layer "F.SilkS")
		)
		(fp_poly
			(pts
				(xy -1.909064 -0.710184) (xy -2.61112 -0.359156) (xy -2.61112 -1.061212)
			)
			(stroke
				(width 0)
				(type default)
			)
			(fill yes)
			(layer "F.SilkS")
		)
		(fp_line
			(start -0.674878 -1.100074)
			(end 0.674878 -1.100074)
			(stroke
				(width 0.1)
				(type default)
			)
			(layer "F.Fab")
		)
		(fp_line
			(start -0.674878 1.100074)
			(end -0.674878 -1.100074)
			(stroke
				(width 0.1)
				(type default)
			)
			(layer "F.Fab")
		)
		(fp_line
			(start 0.674878 -1.100074)
			(end 0.674878 1.100074)
			(stroke
				(width 0.1)
				(type default)
			)
			(layer "F.Fab")
		)
		(fp_line
			(start 0.674878 1.100074)
			(end -0.674878 1.100074)
			(stroke
				(width 0.1)
				(type default)
			)
			(layer "F.Fab")
		)
		(fp_poly
			(pts
				(xy -2.2352 -0.298958) (xy -2.2352 -1.001014) (xy -1.533144 -0.649986)
			)
			(stroke
				(width 0)
				(type default)
			)
			(fill yes)
			(layer "F.Fab")
		)
		(pad "1" smd rect
			(at -0.94996 -0.649986 90)
			(size 0.4318 0.508)
			(layers "F.Cu" "F.Mask" "F.Paste")
			(net "GND")
		)
		(pad "2" smd rect
			(at -0.94996 0 90)
			(size 0.4318 0.508)
			(layers "F.Cu" "F.Mask" "F.Paste")
			(net "P3V3_E1S_EN_0_R")
		)
		(pad "3" smd rect
			(at -0.94996 0.649986 90)
			(size 0.4318 0.508)
			(layers "F.Cu" "F.Mask" "F.Paste")
			(net "P3V3_E1S_UV_0_R")
		)
		(pad "4" smd rect
			(at 0.94996 0.649986 90)
			(size 0.4318 0.508)
			(layers "F.Cu" "F.Mask" "F.Paste")
			(net "GND")
		)
		(pad "5" smd rect
			(at 0.94996 0 90)
			(size 0.4318 0.508)
			(layers "F.Cu" "F.Mask" "F.Paste")
			(net "P3V3_E1S_0_EN_G")
		)
		(pad "6" smd rect
			(at 0.94996 -0.649986 90)
			(size 0.4318 0.508)
			(layers "F.Cu" "F.Mask" "F.Paste")
			(net "P3V3_E1S_0_EN_G")
		)
	)
	(footprint ""
		(layer "F.Cu")
		(at 253.08941 -45.865542 90)
		(property "Reference" "PR3968"
			(at 0 0 90)
			(layer "F.SilkS")
			(hide yes)
			(effects
				(font
					(size 1.27 1.27)
				)
			)
		)
		(property "Value" ""
			(at 0 0 90)
			(layer "F.Fab")
			(effects
				(font
					(size 1.27 1.27)
				)
			)
		)
		(duplicate_pad_numbers_are_jumpers no)
		(fp_line
			(start 0.7874 -0.4064)
			(end 0.7874 0.4064)
			(stroke
				(width 0.1524)
				(type default)
			)
			(layer "F.SilkS")
		)
		(fp_line
			(start -0.7874 -0.4064)
			(end 0.7874 -0.4064)
			(stroke
				(width 0.1524)
				(type default)
			)
			(layer "F.SilkS")
		)
		(fp_line
			(start 0.7874 0.4064)
			(end -0.7874 0.4064)
			(stroke
				(width 0.1524)
				(type default)
			)
			(layer "F.SilkS")
		)
		(fp_line
			(start -0.7874 0.4064)
			(end -0.7874 -0.4064)
			(stroke
				(width 0.1524)
				(type default)
			)
			(layer "F.SilkS")
		)
		(fp_line
			(start -0.12065 -0.305054)
			(end -0.12065 -0.2794)
			(stroke
				(width 0.1)
				(type default)
			)
			(layer "F.Fab")
		)
		(fp_line
			(start -0.67945 -0.305054)
			(end -0.12065 -0.305054)
			(stroke
				(width 0.1)
				(type default)
			)
			(layer "F.Fab")
		)
		(fp_line
			(start 0.67945 -0.3048)
			(end 0.67945 0.3048)
			(stroke
				(width 0.1)
				(type default)
			)
			(layer "F.Fab")
		)
		(fp_line
			(start 0.12065 -0.3048)
			(end 0.67945 -0.3048)
			(stroke
				(width 0.1)
				(type default)
			)
			(layer "F.Fab")
		)
		(fp_line
			(start 0.12065 -0.2794)
			(end 0.12065 -0.3048)
			(stroke
				(width 0.1)
				(type default)
			)
			(layer "F.Fab")
		)
		(fp_line
			(start -0.12065 -0.2794)
			(end 0.12065 -0.2794)
			(stroke
				(width 0.1)
				(type default)
			)
			(layer "F.Fab")
		)
		(fp_line
			(start 0.120396 0.2794)
			(end -0.12065 0.2794)
			(stroke
				(width 0.1)
				(type default)
			)
			(layer "F.Fab")
		)
		(fp_line
			(start -0.12065 0.2794)
			(end -0.12065 0.3048)
			(stroke
				(width 0.1)
				(type default)
			)
			(layer "F.Fab")
		)
		(fp_line
			(start 0.67945 0.3048)
			(end 0.120396 0.3048)
			(stroke
				(width 0.1)
				(type default)
			)
			(layer "F.Fab")
		)
		(fp_line
			(start 0.120396 0.3048)
			(end 0.120396 0.2794)
			(stroke
				(width 0.1)
				(type default)
			)
			(layer "F.Fab")
		)
		(fp_line
			(start -0.12065 0.3048)
			(end -0.67945 0.3048)
			(stroke
				(width 0.1)
				(type default)
			)
			(layer "F.Fab")
		)
		(fp_line
			(start -0.67945 0.3048)
			(end -0.67945 -0.305054)
			(stroke
				(width 0.1)
				(type default)
			)
			(layer "F.Fab")
		)
		(pad "1" smd circle
			(at -0.40005 0 90)
			(size 0 0)
			(layers "F.Cu" "F.Mask" "F.Paste")
			(net "P12V_E1S_CB_0")
		)
		(pad "2" smd circle
			(at 0.40005 0 90)
			(size 0 0)
			(layers "F.Cu" "F.Mask" "F.Paste")
			(net "GND")
		)
	)
)
